(kicad_pcb
	(version 20260206)
	(generator "pcbnew")
	(generator_version "10.0")
	(general
		(thickness 1.6)
		(legacy_teardrops no)
	)
	(paper "A4")
	(title_block
		(title "peb — Lightning_PEB_BRD.brd")
		(comment 1 "Lightning (Wiwynn / Facebook NVMe JBOF) / footprints 693-700 of 2563")
	)
	(layers
		(0 "F.Cu" signal "TOP")
		(4 "In1.Cu" signal "L2GND")
		(6 "In2.Cu" signal "L3")
		(8 "In3.Cu" signal "L4VCC")
		(10 "In4.Cu" signal "L5VCC")
		(12 "In5.Cu" signal "L6")
		(14 "In6.Cu" signal "L7GND")
		(2 "B.Cu" signal "BOTTOM")
		(9 "F.Adhes" user "F.Adhesive")
		(11 "B.Adhes" user "B.Adhesive")
		(13 "F.Paste" user "Package Geometry/Pastemask Top")
		(15 "B.Paste" user "Package Geometry/Pastemask Bottom")
		(5 "F.SilkS" user "Ref Des/Silkscreen Top")
		(7 "B.SilkS" user "Ref Des/Silkscreen Bottom")
		(1 "F.Mask" user "Board Geometry/Soldermask Top")
		(3 "B.Mask" user "Board Geometry/Soldermask Bottom")
		(17 "Dwgs.User" user "User.Drawings")
		(19 "Cmts.User" user "User.Comments")
		(21 "Eco1.User" user "User.Eco1")
		(23 "Eco2.User" user "User.Eco2")
		(25 "Edge.Cuts" user "Board Geometry/Outline")
		(27 "Margin" user)
		(31 "F.CrtYd" user "Package Geometry/Place Bound Top")
		(29 "B.CrtYd" user "Package Geometry/Place Bound Bottom")
		(35 "F.Fab" user "Ref Des/Assembly Top")
		(33 "B.Fab" user "Ref Des/Assembly Bottom")
	)
	(footprint ""
		(layer "F.Cu")
		(at 166.392098 -212.420454 180)
		(property "Reference" "C160"
			(at 0 0 180)
			(layer "F.SilkS")
			(hide yes)
			(effects
				(font
					(size 1.27 1.27)
				)
			)
		)
		(property "Value" "SCD22U10V2KX-1GP"
			(at 1.1811 -2.7051 180)
			(unlocked yes)
			(layer "F.Fab")
			(hide yes)
			(effects
				(font
					(size 1.016 1.016)
					(thickness 0.1524)
				)
			)
		)
		(property "Device Type" "C402H22"
			(at 1.1811 -4.2291 180)
			(unlocked yes)
			(layer "F.Fab")
			(hide yes)
			(effects
				(font
					(size 1.016 1.016)
					(thickness 0.1524)
				)
			)
		)
		(duplicate_pad_numbers_are_jumpers no)
		(fp_rect
			(start -0.4318 0.9525)
			(end 0.4318 -0.9525)
			(stroke
				(width 0)
				(type default)
			)
			(fill no)
			(layer "F.CrtYd")
		)
		(fp_rect
			(start -0.4318 0.9525)
			(end 0.4318 -0.9525)
			(stroke
				(width 0)
				(type default)
			)
			(fill no)
			(layer "F.Fab")
		)
		(pad "1" smd custom
			(at 0 -0.4445 180)
			(size 0.1524 0.1524)
			(layers "F.Cu" "F.Mask" "F.Paste")
			(net "PCIE_TX_CAP_P51")
			(options
				(clearance outline)
				(anchor circle)
			)
			(primitives
				(gr_poly
					(pts
						(arc
							(start 0.3048 -0.2032)
							(mid 0.275042 -0.275042)
							(end 0.2032 -0.3048)
						)
						(arc
							(start -0.2032 -0.3048)
							(mid -0.275042 -0.275042)
							(end -0.3048 -0.2032)
						)
						(arc
							(start -0.3048 0.2032)
							(mid -0.275042 0.275042)
							(end -0.2032 0.3048)
						)
						(arc
							(start 0.2032 0.3048)
							(mid 0.275042 0.275042)
							(end 0.3048 0.2032)
						)
					)
					(width 0)
					(fill yes)
				)
			)
		)
		(pad "2" smd custom
			(at 0 0.4445 180)
			(size 0.1524 0.1524)
			(layers "F.Cu" "F.Mask" "F.Paste")
			(net "PCIE_TX_P51")
			(options
				(clearance outline)
				(anchor circle)
			)
			(primitives
				(gr_poly
					(pts
						(arc
							(start 0.3048 -0.2032)
							(mid 0.275042 -0.275042)
							(end 0.2032 -0.3048)
						)
						(arc
							(start -0.2032 -0.3048)
							(mid -0.275042 -0.275042)
							(end -0.3048 -0.2032)
						)
						(arc
							(start -0.3048 0.2032)
							(mid -0.275042 0.275042)
							(end -0.2032 0.3048)
						)
						(arc
							(start 0.2032 0.3048)
							(mid 0.275042 0.275042)
							(end 0.3048 0.2032)
						)
					)
					(width 0)
					(fill yes)
				)
			)
		)
	)
	(footprint ""
		(layer "F.Cu")
		(at 80.113124 -195.681092 180)
		(property "Reference" "R7933"
			(at 0 0 180)
			(layer "F.SilkS")
			(hide yes)
			(effects
				(font
					(size 1.27 1.27)
				)
			)
		)
		(property "Value" "0R2J-2-GP"
			(at 0.064008 -3.993896 180)
			(unlocked yes)
			(layer "F.Fab")
			(hide yes)
			(effects
				(font
					(size 1.016 1.016)
					(thickness 0.1524)
				)
			)
		)
		(property "Device Type" "R402H16"
			(at 0.064008 -5.517896 180)
			(unlocked yes)
			(layer "F.Fab")
			(hide yes)
			(effects
				(font
					(size 1.016 1.016)
					(thickness 0.1524)
				)
			)
		)
		(duplicate_pad_numbers_are_jumpers no)
		(fp_line
			(start 0.508 -0.9398)
			(end -0.508 -0.9398)
			(stroke
				(width 0.1524)
				(type default)
			)
			(layer "F.SilkS")
		)
		(fp_line
			(start -0.508 -0.9398)
			(end -0.508 0.9398)
			(stroke
				(width 0.1524)
				(type default)
			)
			(layer "F.SilkS")
		)
		(fp_rect
			(start -0.508 0.9398)
			(end 0.508 -0.9398)
			(stroke
				(width 0)
				(type default)
			)
			(fill no)
			(layer "F.CrtYd")
		)
		(fp_rect
			(start -0.508 0.9398)
			(end 0.508 -0.9398)
			(stroke
				(width 0)
				(type default)
			)
			(fill no)
			(layer "F.Fab")
		)
		(pad "1" smd custom
			(at 0 -0.4445 180)
			(size 0.1397 0.1397)
			(layers "F.Cu" "F.Mask" "F.Paste")
			(net "SSD_PRSNT#10")
			(options
				(clearance outline)
				(anchor circle)
			)
			(primitives
				(gr_poly
					(pts
						(arc
							(start -0.1778 -0.2794)
							(mid -0.249642 -0.249642)
							(end -0.2794 -0.1778)
						)
						(arc
							(start -0.2794 0.1778)
							(mid -0.249642 0.249642)
							(end -0.1778 0.2794)
						)
						(arc
							(start 0.1778 0.2794)
							(mid 0.249642 0.249642)
							(end 0.2794 0.1778)
						)
						(arc
							(start 0.2794 -0.1778)
							(mid 0.249642 -0.249642)
							(end 0.1778 -0.2794)
						)
					)
					(width 0)
					(fill yes)
				)
			)
		)
		(pad "2" smd custom
			(at 0 0.4445 180)
			(size 0.1397 0.1397)
			(layers "F.Cu" "F.Mask" "F.Paste")
			(net "SSD_PRSNT#10_R")
			(options
				(clearance outline)
				(anchor circle)
			)
			(primitives
				(gr_poly
					(pts
						(arc
							(start -0.1778 -0.2794)
							(mid -0.249642 -0.249642)
							(end -0.2794 -0.1778)
						)
						(arc
							(start -0.2794 0.1778)
							(mid -0.249642 0.249642)
							(end -0.1778 0.2794)
						)
						(arc
							(start 0.1778 0.2794)
							(mid 0.249642 0.249642)
							(end 0.2794 0.1778)
						)
						(arc
							(start 0.2794 -0.1778)
							(mid 0.249642 -0.249642)
							(end 0.1778 -0.2794)
						)
					)
					(width 0)
					(fill yes)
				)
			)
		)
	)
	(footprint ""
		(layer "F.Cu")
		(at 50.292 -132.842)
		(property "Reference" "TP219"
			(at 0 0 0)
			(layer "F.SilkS")
			(hide yes)
			(effects
				(font
					(size 1.27 1.27)
				)
			)
		)
		(property "Value" "TPAD28-2-GP"
			(at -0.0127 -1.6637 0)
			(unlocked yes)
			(layer "F.Fab")
			(hide yes)
			(effects
				(font
					(size 1.016 1.016)
					(thickness 0.1524)
				)
			)
		)
		(property "Device Type" "TPAD28"
			(at -0.0127 -3.1877 0)
			(unlocked yes)
			(layer "F.Fab")
			(hide yes)
			(effects
				(font
					(size 1.016 1.016)
					(thickness 0.1524)
				)
			)
		)
		(duplicate_pad_numbers_are_jumpers no)
		(fp_poly
			(pts
				(arc
					(start 0.3556 0)
					(mid -0.3556 0)
					(end 0.3556 0)
				)
			)
			(stroke
				(width 0)
				(type default)
			)
			(fill no)
			(layer "F.CrtYd")
		)
		(fp_poly
			(pts
				(arc
					(start 0.6096 0)
					(mid -0.6096 0)
					(end 0.6096 0)
				)
			)
			(stroke
				(width 0)
				(type default)
			)
			(fill no)
			(layer "F.Fab")
		)
		(pad "1" smd circle
			(at 0 0)
			(size 0.7112 0.7112)
			(layers "F.Cu" "F.Mask" "F.Paste")
			(net "DACR")
		)
	)
	(footprint ""
		(layer "F.Cu")
		(at 77.0382 -195.6562 180)
		(property "Reference" "R9039"
			(at 0 0 180)
			(layer "F.SilkS")
			(hide yes)
			(effects
				(font
					(size 1.27 1.27)
				)
			)
		)
		(property "Value" "4K7R2F-GP"
			(at 0.064008 -3.993896 180)
			(unlocked yes)
			(layer "F.Fab")
			(hide yes)
			(effects
				(font
					(size 1.016 1.016)
					(thickness 0.1524)
				)
			)
		)
		(property "Device Type" "R402H16"
			(at 0.064008 -5.517896 180)
			(unlocked yes)
			(layer "F.Fab")
			(hide yes)
			(effects
				(font
					(size 1.016 1.016)
					(thickness 0.1524)
				)
			)
		)
		(duplicate_pad_numbers_are_jumpers no)
		(fp_line
			(start 0.508 -0.9398)
			(end -0.508 -0.9398)
			(stroke
				(width 0.1524)
				(type default)
			)
			(layer "F.SilkS")
		)
		(fp_line
			(start -0.508 -0.9398)
			(end -0.508 0.9398)
			(stroke
				(width 0.1524)
				(type default)
			)
			(layer "F.SilkS")
		)
		(fp_rect
			(start -0.508 0.9398)
			(end 0.508 -0.9398)
			(stroke
				(width 0)
				(type default)
			)
			(fill no)
			(layer "F.CrtYd")
		)
		(fp_rect
			(start -0.508 0.9398)
			(end 0.508 -0.9398)
			(stroke
				(width 0)
				(type default)
			)
			(fill no)
			(layer "F.Fab")
		)
		(pad "1" smd custom
			(at 0 -0.4445 180)
			(size 0.1397 0.1397)
			(layers "F.Cu" "F.Mask" "F.Paste")
			(net "SSD_PERST#10")
			(options
				(clearance outline)
				(anchor circle)
			)
			(primitives
				(gr_poly
					(pts
						(arc
							(start -0.1778 -0.2794)
							(mid -0.249642 -0.249642)
							(end -0.2794 -0.1778)
						)
						(arc
							(start -0.2794 0.1778)
							(mid -0.249642 0.249642)
							(end -0.1778 0.2794)
						)
						(arc
							(start 0.1778 0.2794)
							(mid 0.249642 0.249642)
							(end 0.2794 0.1778)
						)
						(arc
							(start 0.2794 -0.1778)
							(mid 0.249642 -0.249642)
							(end 0.1778 -0.2794)
						)
					)
					(width 0)
					(fill yes)
				)
			)
		)
		(pad "2" smd custom
			(at 0 0.4445 180)
			(size 0.1397 0.1397)
			(layers "F.Cu" "F.Mask" "F.Paste")
			(net "GND")
			(options
				(clearance outline)
				(anchor circle)
			)
			(primitives
				(gr_poly
					(pts
						(arc
							(start -0.1778 -0.2794)
							(mid -0.249642 -0.249642)
							(end -0.2794 -0.1778)
						)
						(arc
							(start -0.2794 0.1778)
							(mid -0.249642 0.249642)
							(end -0.1778 0.2794)
						)
						(arc
							(start 0.1778 0.2794)
							(mid 0.249642 0.249642)
							(end 0.2794 0.1778)
						)
						(arc
							(start 0.2794 -0.1778)
							(mid 0.249642 -0.249642)
							(end 0.1778 -0.2794)
						)
					)
					(width 0)
					(fill yes)
				)
			)
		)
	)
	(footprint ""
		(layer "F.Cu")
		(at 64.389 -131.953 180)
		(property "Reference" "R5766"
			(at 0 0 180)
			(layer "F.SilkS")
			(hide yes)
			(effects
				(font
					(size 1.27 1.27)
				)
			)
		)
		(property "Value" "1KR2F-3-GP"
			(at 0.064008 -3.993896 180)
			(unlocked yes)
			(layer "F.Fab")
			(hide yes)
			(effects
				(font
					(size 1.016 1.016)
					(thickness 0.1524)
				)
			)
		)
		(property "Device Type" "R402H16"
			(at 0.064008 -5.517896 180)
			(unlocked yes)
			(layer "F.Fab")
			(hide yes)
			(effects
				(font
					(size 1.016 1.016)
					(thickness 0.1524)
				)
			)
		)
		(duplicate_pad_numbers_are_jumpers no)
		(fp_line
			(start 0.508 -0.9398)
			(end -0.508 -0.9398)
			(stroke
				(width 0.1524)
				(type default)
			)
			(layer "F.SilkS")
		)
		(fp_line
			(start -0.508 -0.9398)
			(end -0.508 0.9398)
			(stroke
				(width 0.1524)
				(type default)
			)
			(layer "F.SilkS")
		)
		(fp_rect
			(start -0.508 0.9398)
			(end 0.508 -0.9398)
			(stroke
				(width 0)
				(type default)
			)
			(fill no)
			(layer "F.CrtYd")
		)
		(fp_rect
			(start -0.508 0.9398)
			(end 0.508 -0.9398)
			(stroke
				(width 0)
				(type default)
			)
			(fill no)
			(layer "F.Fab")
		)
		(pad "1" smd custom
			(at 0 -0.4445 180)
			(size 0.1397 0.1397)
			(layers "F.Cu" "F.Mask" "F.Paste")
			(net "ADC_12V")
			(options
				(clearance outline)
				(anchor circle)
			)
			(primitives
				(gr_poly
					(pts
						(arc
							(start -0.1778 -0.2794)
							(mid -0.249642 -0.249642)
							(end -0.2794 -0.1778)
						)
						(arc
							(start -0.2794 0.1778)
							(mid -0.249642 0.249642)
							(end -0.1778 0.2794)
						)
						(arc
							(start 0.1778 0.2794)
							(mid 0.249642 0.249642)
							(end 0.2794 0.1778)
						)
						(arc
							(start 0.2794 -0.1778)
							(mid 0.249642 -0.249642)
							(end 0.1778 -0.2794)
						)
					)
					(width 0)
					(fill yes)
				)
			)
		)
		(pad "2" smd custom
			(at 0 0.4445 180)
			(size 0.1397 0.1397)
			(layers "F.Cu" "F.Mask" "F.Paste")
			(net "GND")
			(options
				(clearance outline)
				(anchor circle)
			)
			(primitives
				(gr_poly
					(pts
						(arc
							(start -0.1778 -0.2794)
							(mid -0.249642 -0.249642)
							(end -0.2794 -0.1778)
						)
						(arc
							(start -0.2794 0.1778)
							(mid -0.249642 0.249642)
							(end -0.1778 0.2794)
						)
						(arc
							(start 0.1778 0.2794)
							(mid 0.249642 0.249642)
							(end 0.2794 0.1778)
						)
						(arc
							(start 0.2794 -0.1778)
							(mid 0.249642 -0.249642)
							(end 0.1778 -0.2794)
						)
					)
					(width 0)
					(fill yes)
				)
			)
		)
	)
	(footprint ""
		(layer "F.Cu")
		(at 159.385 -97.9424 180)
		(property "Reference" "R60"
			(at 0 0 180)
			(layer "F.SilkS")
			(hide yes)
			(effects
				(font
					(size 1.27 1.27)
				)
			)
		)
		(property "Value" "10KR2F-2-GP"
			(at 0.064008 -3.993896 180)
			(unlocked yes)
			(layer "F.Fab")
			(hide yes)
			(effects
				(font
					(size 1.016 1.016)
					(thickness 0.1524)
				)
			)
		)
		(property "Device Type" "R402H16"
			(at 0.064008 -5.517896 180)
			(unlocked yes)
			(layer "F.Fab")
			(hide yes)
			(effects
				(font
					(size 1.016 1.016)
					(thickness 0.1524)
				)
			)
		)
		(duplicate_pad_numbers_are_jumpers no)
		(fp_line
			(start 0.508 -0.9398)
			(end -0.508 -0.9398)
			(stroke
				(width 0.1524)
				(type default)
			)
			(layer "F.SilkS")
		)
		(fp_line
			(start -0.508 -0.9398)
			(end -0.508 0.9398)
			(stroke
				(width 0.1524)
				(type default)
			)
			(layer "F.SilkS")
		)
		(fp_rect
			(start -0.508 0.9398)
			(end 0.508 -0.9398)
			(stroke
				(width 0)
				(type default)
			)
			(fill no)
			(layer "F.CrtYd")
		)
		(fp_rect
			(start -0.508 0.9398)
			(end 0.508 -0.9398)
			(stroke
				(width 0)
				(type default)
			)
			(fill no)
			(layer "F.Fab")
		)
		(pad "1" smd custom
			(at 0 -0.4445 180)
			(size 0.1397 0.1397)
			(layers "F.Cu" "F.Mask" "F.Paste")
			(net "CLKGEN_OE3")
			(options
				(clearance outline)
				(anchor circle)
			)
			(primitives
				(gr_poly
					(pts
						(arc
							(start -0.1778 -0.2794)
							(mid -0.249642 -0.249642)
							(end -0.2794 -0.1778)
						)
						(arc
							(start -0.2794 0.1778)
							(mid -0.249642 0.249642)
							(end -0.1778 0.2794)
						)
						(arc
							(start 0.1778 0.2794)
							(mid 0.249642 0.249642)
							(end 0.2794 0.1778)
						)
						(arc
							(start 0.2794 -0.1778)
							(mid 0.249642 -0.249642)
							(end 0.1778 -0.2794)
						)
					)
					(width 0)
					(fill yes)
				)
			)
		)
		(pad "2" smd custom
			(at 0 0.4445 180)
			(size 0.1397 0.1397)
			(layers "F.Cu" "F.Mask" "F.Paste")
			(net "P1V8_CLKGEN")
			(options
				(clearance outline)
				(anchor circle)
			)
			(primitives
				(gr_poly
					(pts
						(arc
							(start -0.1778 -0.2794)
							(mid -0.249642 -0.249642)
							(end -0.2794 -0.1778)
						)
						(arc
							(start -0.2794 0.1778)
							(mid -0.249642 0.249642)
							(end -0.1778 0.2794)
						)
						(arc
							(start 0.1778 0.2794)
							(mid 0.249642 0.249642)
							(end 0.2794 0.1778)
						)
						(arc
							(start 0.2794 -0.1778)
							(mid 0.249642 -0.249642)
							(end 0.1778 -0.2794)
						)
					)
					(width 0)
					(fill yes)
				)
			)
		)
	)
	(footprint ""
		(layer "F.Cu")
		(at 219.456 -13.4112 -90)
		(property "Reference" "R714"
			(at 0 0 270)
			(layer "F.SilkS")
			(hide yes)
			(effects
				(font
					(size 1.27 1.27)
				)
			)
		)
		(property "Value" "4K7R2F-GP"
			(at 0.064008 -3.993896 270)
			(unlocked yes)
			(layer "F.Fab")
			(hide yes)
			(effects
				(font
					(size 1.016 1.016)
					(thickness 0.1524)
				)
			)
		)
		(property "Device Type" "R402H16"
			(at 0.064008 -5.517896 270)
			(unlocked yes)
			(layer "F.Fab")
			(hide yes)
			(effects
				(font
					(size 1.016 1.016)
					(thickness 0.1524)
				)
			)
		)
		(duplicate_pad_numbers_are_jumpers no)
		(fp_line
			(start -0.508 -0.9398)
			(end -0.508 0.9398)
			(stroke
				(width 0.1524)
				(type default)
			)
			(layer "F.SilkS")
		)
		(fp_line
			(start 0.508 -0.9398)
			(end -0.508 -0.9398)
			(stroke
				(width 0.1524)
				(type default)
			)
			(layer "F.SilkS")
		)
		(fp_rect
			(start -0.508 0.9398)
			(end 0.508 -0.9398)
			(stroke
				(width 0)
				(type default)
			)
			(fill no)
			(layer "F.CrtYd")
		)
		(fp_rect
			(start -0.508 0.9398)
			(end 0.508 -0.9398)
			(stroke
				(width 0)
				(type default)
			)
			(fill no)
			(layer "F.Fab")
		)
		(pad "1" smd custom
			(at 0 -0.4445 270)
			(size 0.1397 0.1397)
			(layers "F.Cu" "F.Mask" "F.Paste")
			(net "U81_Y")
			(options
				(clearance outline)
				(anchor circle)
			)
			(primitives
				(gr_poly
					(pts
						(arc
							(start -0.1778 -0.2794)
							(mid -0.249642 -0.249642)
							(end -0.2794 -0.1778)
						)
						(arc
							(start -0.2794 0.1778)
							(mid -0.249642 0.249642)
							(end -0.1778 0.2794)
						)
						(arc
							(start 0.1778 0.2794)
							(mid 0.249642 0.249642)
							(end 0.2794 0.1778)
						)
						(arc
							(start 0.2794 -0.1778)
							(mid 0.249642 -0.249642)
							(end 0.1778 -0.2794)
						)
					)
					(width 0)
					(fill yes)
				)
			)
		)
		(pad "2" smd custom
			(at 0 0.4445 270)
			(size 0.1397 0.1397)
			(layers "F.Cu" "F.Mask" "F.Paste")
			(net "P3V3_STBY")
			(options
				(clearance outline)
				(anchor circle)
			)
			(primitives
				(gr_poly
					(pts
						(arc
							(start -0.1778 -0.2794)
							(mid -0.249642 -0.249642)
							(end -0.2794 -0.1778)
						)
						(arc
							(start -0.2794 0.1778)
							(mid -0.249642 0.249642)
							(end -0.1778 0.2794)
						)
						(arc
							(start 0.1778 0.2794)
							(mid 0.249642 0.249642)
							(end 0.2794 0.1778)
						)
						(arc
							(start 0.2794 -0.1778)
							(mid 0.249642 -0.249642)
							(end 0.1778 -0.2794)
						)
					)
					(width 0)
					(fill yes)
				)
			)
		)
	)
	(footprint ""
		(layer "F.Cu")
		(at 11.176 -70.3072 -90)
		(property "Reference" "R385"
			(at 0 0 270)
			(layer "F.SilkS")
			(hide yes)
			(effects
				(font
					(size 1.27 1.27)
				)
			)
		)
		(property "Value" "0R2J-2-GP"
			(at 0.064008 -3.993896 270)
			(unlocked yes)
			(layer "F.Fab")
			(hide yes)
			(effects
				(font
					(size 1.016 1.016)
					(thickness 0.1524)
				)
			)
		)
		(property "Device Type" "R402H16"
			(at 0.064008 -5.517896 270)
			(unlocked yes)
			(layer "F.Fab")
			(hide yes)
			(effects
				(font
					(size 1.016 1.016)
					(thickness 0.1524)
				)
			)
		)
		(duplicate_pad_numbers_are_jumpers no)
		(fp_line
			(start -0.508 -0.9398)
			(end -0.508 0.9398)
			(stroke
				(width 0.1524)
				(type default)
			)
			(layer "F.SilkS")
		)
		(fp_line
			(start 0.508 -0.9398)
			(end -0.508 -0.9398)
			(stroke
				(width 0.1524)
				(type default)
			)
			(layer "F.SilkS")
		)
		(fp_rect
			(start -0.508 0.9398)
			(end 0.508 -0.9398)
			(stroke
				(width 0)
				(type default)
			)
			(fill no)
			(layer "F.CrtYd")
		)
		(fp_rect
			(start -0.508 0.9398)
			(end 0.508 -0.9398)
			(stroke
				(width 0)
				(type default)
			)
			(fill no)
			(layer "F.Fab")
		)
		(pad "1" smd custom
			(at 0 -0.4445 270)
			(size 0.1397 0.1397)
			(layers "F.Cu" "F.Mask" "F.Paste")
			(net "XTAL_IN_I210")
			(options
				(clearance outline)
				(anchor circle)
			)
			(primitives
				(gr_poly
					(pts
						(arc
							(start -0.1778 -0.2794)
							(mid -0.249642 -0.249642)
							(end -0.2794 -0.1778)
						)
						(arc
							(start -0.2794 0.1778)
							(mid -0.249642 0.249642)
							(end -0.1778 0.2794)
						)
						(arc
							(start 0.1778 0.2794)
							(mid 0.249642 0.249642)
							(end 0.2794 0.1778)
						)
						(arc
							(start 0.2794 -0.1778)
							(mid 0.249642 -0.249642)
							(end 0.1778 -0.2794)
						)
					)
					(width 0)
					(fill yes)
				)
			)
		)
		(pad "2" smd custom
			(at 0 0.4445 270)
			(size 0.1397 0.1397)
			(layers "F.Cu" "F.Mask" "F.Paste")
			(net "XTAL_IN_I210_R")
			(options
				(clearance outline)
				(anchor circle)
			)
			(primitives
				(gr_poly
					(pts
						(arc
							(start -0.1778 -0.2794)
							(mid -0.249642 -0.249642)
							(end -0.2794 -0.1778)
						)
						(arc
							(start -0.2794 0.1778)
							(mid -0.249642 0.249642)
							(end -0.1778 0.2794)
						)
						(arc
							(start 0.1778 0.2794)
							(mid 0.249642 0.249642)
							(end 0.2794 0.1778)
						)
						(arc
							(start 0.2794 -0.1778)
							(mid 0.249642 -0.249642)
							(end 0.1778 -0.2794)
						)
					)
					(width 0)
					(fill yes)
				)
			)
		)
	)
)
